# BASEBOARD_FAB2 (Tioga Pass) — schematic netlist excerpt (pin names and nets, part order shuffled) for the footprints in the layout excerpt that follows; sources: Cadence DE-HDL packaged netlist, KiCad conversion of Wiwynn_Tioga_Pass_MB.brd

C6P7  CAP  10UF 16V 10% X6S  pkg 0805  page 203 : A = VR_FET_SW_P12V_STBY_PVCCIN_CPU0 ; B = GND
R2U36  RES  20.0 1% EMPTY  pkg 0402  page 108 : A = SMB_SLOTX24_PCH_STBY_LVC3_SCL ; B = SMB_SLOTX24_STBY_LVC3_SCL_R2
R4R3  RES  150.0 1% CHIP  pkg 0402  page 93 : A = PVCCIO_CPU0 ; B = H_CPU0_PROCHOT_G_N

(kicad_pcb
	(version 20260206)
	(generator "pcbnew")
	(generator_version "10.0")
	(general
		(thickness 1.6)
		(legacy_teardrops no)
	)
	(paper "A4")
	(title_block
		(title "Wiwynn_Tioga_Pass_MB.brd")
		(comment 1 "Tioga Pass / footprints 4730-4732 of 4770")
	)
	(layers
		(0 "F.Cu" signal "TOP")
		(4 "In1.Cu" signal "L2GND")
		(6 "In2.Cu" signal "L3")
		(8 "In3.Cu" signal "L4GND")
		(10 "In4.Cu" signal "L5")
		(12 "In5.Cu" signal "L6GND")
		(14 "In6.Cu" signal "L7VCC")
		(16 "In7.Cu" signal "L8VCC")
		(18 "In8.Cu" signal "L9GND")
		(20 "In9.Cu" signal "L10")
		(22 "In10.Cu" signal "L11GND")
		(24 "In11.Cu" signal "L12")
		(26 "In12.Cu" signal "L13GND")
		(2 "B.Cu" signal "BOTTOM")
		(9 "F.Adhes" user "F.Adhesive")
		(11 "B.Adhes" user "B.Adhesive")
		(13 "F.Paste" user "Package Geometry/Pastemask Top")
		(15 "B.Paste" user "Package Geometry/Pastemask Bottom")
		(5 "F.SilkS" user "Ref Des/Silkscreen Top")
		(7 "B.SilkS" user "Ref Des/Silkscreen Bottom")
		(1 "F.Mask" user "Board Geometry/Soldermask Top")
		(3 "B.Mask" user "Board Geometry/Soldermask Bottom")
		(17 "Dwgs.User" user "User.Drawings")
		(19 "Cmts.User" user "User.Comments")
		(21 "Eco1.User" user "User.Eco1")
		(23 "Eco2.User" user "User.Eco2")
		(25 "Edge.Cuts" user "Board Geometry/Outline")
		(27 "Margin" user)
		(31 "F.CrtYd" user "Package Geometry/Place Bound Top")
		(29 "B.CrtYd" user "Package Geometry/Place Bound Bottom")
		(35 "F.Fab" user "Ref Des/Assembly Top")
		(33 "B.Fab" user "Ref Des/Assembly Bottom")
	)
	(footprint ""
		(layer "B.Cu")
		(at 197.950328 -84.493862 90)
		(property "Reference" "C6P7"
			(at 0 0 90)
			(layer "B.SilkS")
			(hide yes)
			(effects
				(font
					(size 1.27 1.27)
				)
				(justify mirror)
			)
		)
		(property "Value" ""
			(at 0 0 90)
			(layer "B.Fab")
			(effects
				(font
					(size 1.27 1.27)
				)
				(justify mirror)
			)
		)
		(duplicate_pad_numbers_are_jumpers no)
		(fp_rect
			(start -0.7239 -0.2159)
			(end 0.7239 1.9939)
			(stroke
				(width 0)
				(type default)
			)
			(fill no)
			(layer "B.CrtYd")
		)
		(fp_line
			(start 0.7239 -0.2159)
			(end 0.7239 1.9939)
			(stroke
				(width 0.1)
				(type default)
			)
			(layer "B.Fab")
		)
		(fp_line
			(start -0.7239 -0.2159)
			(end 0.7239 -0.2159)
			(stroke
				(width 0.1)
				(type default)
			)
			(layer "B.Fab")
		)
		(fp_line
			(start 0.7239 1.9939)
			(end -0.7239 1.9939)
			(stroke
				(width 0.1)
				(type default)
			)
			(layer "B.Fab")
		)
		(fp_line
			(start -0.7239 1.9939)
			(end -0.7239 -0.2159)
			(stroke
				(width 0.1)
				(type default)
			)
			(layer "B.Fab")
		)
		(pad "1" smd rect
			(at 0 0 270)
			(size 1.27 1.016)
			(layers "B.Cu" "B.Mask" "B.Paste")
			(net "VR_FET_SW_P12V_STBY_PVCCIN_CPU0")
		)
		(pad "2" smd rect
			(at 0 1.778 270)
			(size 1.27 1.016)
			(layers "B.Cu" "B.Mask" "B.Paste")
			(net "GND")
		)
		(zone
			(layer "B.Cu")
			(hatch none 0.5)
			(connect_pads
				(clearance 0)
			)
			(min_thickness 0.25)
			(keepout
				(tracks not_allowed)
				(vias allowed)
				(pads allowed)
				(copperpour not_allowed)
				(footprints allowed)
			)
			(placement
				(enabled no)
				(sheetname "")
			)
			(fill
				(thermal_gap 0.5)
				(thermal_bridge_width 0.5)
				(island_removal_mode 0)
			)
			(polygon
				(pts
					(xy 198.458328 -83.858862) (xy 199.220328 -83.858862) (xy 199.220328 -85.128862) (xy 198.458328 -85.128862)
				)
			)
		)
	)
	(footprint ""
		(layer "B.Cu")
		(at 338.0232 -56.8833)
		(property "Reference" "R4R3"
			(at 0 0 0)
			(layer "B.SilkS")
			(hide yes)
			(effects
				(font
					(size 1.27 1.27)
				)
				(justify mirror)
			)
		)
		(property "Value" ""
			(at 0 0 0)
			(layer "B.Fab")
			(effects
				(font
					(size 1.27 1.27)
				)
				(justify mirror)
			)
		)
		(duplicate_pad_numbers_are_jumpers no)
		(fp_poly
			(pts
				(xy 0.2794 -0.1016) (xy -0.2794 -0.1016) (xy -0.2794 0.9906) (xy 0.2794 0.9906)
			)
			(stroke
				(width 0)
				(type default)
			)
			(fill no)
			(layer "B.CrtYd")
		)
		(fp_line
			(start -0.2794 -0.1016)
			(end 0.2794 -0.1016)
			(stroke
				(width 0.1)
				(type default)
			)
			(layer "B.Fab")
		)
		(fp_line
			(start -0.2794 0.9906)
			(end -0.2794 -0.1016)
			(stroke
				(width 0.1)
				(type default)
			)
			(layer "B.Fab")
		)
		(fp_line
			(start 0.2794 -0.1016)
			(end 0.2794 0.9906)
			(stroke
				(width 0.1)
				(type default)
			)
			(layer "B.Fab")
		)
		(fp_line
			(start 0.2794 0.9906)
			(end -0.2794 0.9906)
			(stroke
				(width 0.1)
				(type default)
			)
			(layer "B.Fab")
		)
		(pad "1" smd rect
			(at 0 0 180)
			(size 0.508 0.508)
			(layers "B.Cu" "B.Mask" "B.Paste")
			(net "PVCCIO_CPU0")
		)
		(pad "2" smd rect
			(at 0 0.889 180)
			(size 0.508 0.508)
			(layers "B.Cu" "B.Mask" "B.Paste")
			(net "H_CPU0_PROCHOT_G_N")
		)
		(zone
			(layer "B.Cu")
			(hatch none 0.5)
			(connect_pads
				(clearance 0)
			)
			(min_thickness 0.25)
			(keepout
				(tracks allowed)
				(vias not_allowed)
				(pads allowed)
				(copperpour not_allowed)
				(footprints allowed)
			)
			(placement
				(enabled no)
				(sheetname "")
			)
			(fill
				(thermal_gap 0.5)
				(thermal_bridge_width 0.5)
				(island_removal_mode 0)
			)
			(polygon
				(pts
					(xy 338.2772 -56.6293) (xy 337.7692 -56.6293) (xy 337.7692 -56.2483) (xy 338.2772 -56.2483)
				)
			)
		)
		(zone
			(layer "B.Cu")
			(hatch none 0.5)
			(connect_pads
				(clearance 0)
			)
			(min_thickness 0.25)
			(keepout
				(tracks not_allowed)
				(vias allowed)
				(pads allowed)
				(copperpour not_allowed)
				(footprints allowed)
			)
			(placement
				(enabled no)
				(sheetname "")
			)
			(fill
				(thermal_gap 0.5)
				(thermal_bridge_width 0.5)
				(island_removal_mode 0)
			)
			(polygon
				(pts
					(xy 338.2772 -56.2483) (xy 337.7692 -56.2483) (xy 337.7692 -56.6293) (xy 338.2772 -56.6293)
				)
			)
		)
	)
	(footprint ""
		(layer "B.Cu")
		(at 468.181944 -9.64692 180)
		(property "Reference" "R2U36"
			(at 0.8382 -0.67818 180)
			(unlocked yes)
			(layer "B.SilkS")
			(effects
				(font
					(size 0.4064 0.254)
					(thickness 0.1524)
				)
				(justify left mirror)
			)
		)
		(property "Value" ""
			(at 0 0 0)
			(layer "B.Fab")
			(effects
				(font
					(size 1.27 1.27)
				)
				(justify mirror)
			)
		)
		(duplicate_pad_numbers_are_jumpers no)
		(fp_poly
			(pts
				(xy 0.2794 -0.1016) (xy -0.2794 -0.1016) (xy -0.2794 0.9906) (xy 0.2794 0.9906)
			)
			(stroke
				(width 0)
				(type default)
			)
			(fill no)
			(layer "B.CrtYd")
		)
		(fp_line
			(start 0.2794 0.9906)
			(end -0.2794 0.9906)
			(stroke
				(width 0.1)
				(type default)
			)
			(layer "B.Fab")
		)
		(fp_line
			(start 0.2794 -0.1016)
			(end 0.2794 0.9906)
			(stroke
				(width 0.1)
				(type default)
			)
			(layer "B.Fab")
		)
		(fp_line
			(start -0.2794 0.9906)
			(end -0.2794 -0.1016)
			(stroke
				(width 0.1)
				(type default)
			)
			(layer "B.Fab")
		)
		(fp_line
			(start -0.2794 -0.1016)
			(end 0.2794 -0.1016)
			(stroke
				(width 0.1)
				(type default)
			)
			(layer "B.Fab")
		)
		(pad "1" smd rect
			(at 0 0)
			(size 0.508 0.508)
			(layers "B.Cu" "B.Mask" "B.Paste")
			(net "SMB_SLOTX24_PCH_STBY_LVC3_SCL")
		)
		(pad "2" smd rect
			(at 0 0.889)
			(size 0.508 0.508)
			(layers "B.Cu" "B.Mask" "B.Paste")
			(net "SMB_SLOTX24_STBY_LVC3_SCL_R2")
		)
		(zone
			(layer "B.Cu")
			(hatch none 0.5)
			(connect_pads
				(clearance 0)
			)
			(min_thickness 0.25)
			(keepout
				(tracks not_allowed)
				(vias allowed)
				(pads allowed)
				(copperpour not_allowed)
				(footprints allowed)
			)
			(placement
				(enabled no)
				(sheetname "")
			)
			(fill
				(thermal_gap 0.5)
				(thermal_bridge_width 0.5)
				(island_removal_mode 0)
			)
			(polygon
				(pts
					(xy 467.927944 -10.28192) (xy 468.435944 -10.28192) (xy 468.435944 -9.90092) (xy 467.927944 -9.90092)
				)
			)
		)
		(zone
			(layer "B.Cu")
			(hatch none 0.5)
			(connect_pads
				(clearance 0)
			)
			(min_thickness 0.25)
			(keepout
				(tracks allowed)
				(vias not_allowed)
				(pads allowed)
				(copperpour not_allowed)
				(footprints allowed)
			)
			(placement
				(enabled no)
				(sheetname "")
			)
			(fill
				(thermal_gap 0.5)
				(thermal_bridge_width 0.5)
				(island_removal_mode 0)
			)
			(polygon
				(pts
					(xy 467.927944 -9.90092) (xy 468.435944 -9.90092) (xy 468.435944 -10.28192) (xy 467.927944 -10.28192)
				)
			)
		)
	)
)
